# T6G (Grand Teton) — schematic netlist excerpt (pin names and nets, part order shuffled) for the footprints in the layout excerpt that follows; sources: Cadence DE-HDL packaged netlist, KiCad conversion of 04192023_DAF0TMB3IC0_F0TG_MB_C_brd_V02_OCP.brd

J29  SCONN288_DDR506112002KQ  IO  pkg DDR288S_1-1VXC  page 107
  VIN_BULK0  = P12V_MEM_CPU1
  RFU0  = NC
  VIN_MGMT  = P3V3_AUX
  HSCL  = I3C_SPD_DDRJ_CPU1_SCL
  HSDA  = I3C_SPD_DDRJ_CPU1_SDA
  VSS0  = GND
  DQ0_A  = M_J_CPU1_SA_DQ<0>
  VSS1  = GND
  DQ1_A  = M_J_CPU1_SA_DQ<1>
  VSS2  = GND
  DQS0_A_T  = M_J_CPU1_SA_DQS_DP<0>
  DQS0_A_C  = M_J_CPU1_SA_DQS_DN<0>
  VSS3  = GND
  DQ4_A  = M_J_CPU1_SA_DQ<4>
  VSS4  = GND
  DQ5_A  = M_J_CPU1_SA_DQ<5>
  VSS5  = GND
  DQ8_A  = M_J_CPU1_SA_DQ<8>
  VSS6  = GND
  DQ9_A  = M_J_CPU1_SA_DQ<9>
  VSS7  = GND
  DQS1_A_T  = M_J_CPU1_SA_DQS_DP<1>
  DQS1_A_C  = M_J_CPU1_SA_DQS_DN<1>
  VSS8  = GND
  DQ12_A  = M_J_CPU1_SA_DQ<12>
  VSS9  = GND
  DQ13_A  = M_J_CPU1_SA_DQ<13>
  VSS10  = GND
  DQ16_A  = M_J_CPU1_SA_DQ<16>
  VSS11  = GND
  DQ17_A  = M_J_CPU1_SA_DQ<17>
  VSS12  = GND
  DQS2_A_T  = M_J_CPU1_SA_DQS_DP<2>
  DQS2_A_C  = M_J_CPU1_SA_DQS_DN<2>
  VSS13  = GND
  DQ20_A  = M_J_CPU1_SA_DQ<20>
  VSS14  = GND
  DQ21_A  = M_J_CPU1_SA_DQ<21>
  VSS15  = GND
  DQ24_A  = M_J_CPU1_SA_DQ<24>
  VSS16  = GND
  DQ25_A  = M_J_CPU1_SA_DQ<25>
  VSS17  = GND
  DQS3_A_T  = M_J_CPU1_SA_DQS_DP<3>
  DQS3_A_C  = M_J_CPU1_SA_DQS_DN<3>
  VSS18  = GND
  DQ28_A  = M_J_CPU1_SA_DQ<28>
  VSS19  = GND
  DQ29_A  = M_J_CPU1_SA_DQ<29>
  VSS20  = GND
  CB0_A  = M_J_CPU1_SA_CB<0>
  VSS21  = GND
  CB1_A  = M_J_CPU1_SA_CB<1>
  VSS22  = GND
  DQS4_A_T  = M_J_CPU1_SA_DQS_DP<4>
  DQS4_A_C  = M_J_CPU1_SA_DQS_DN<4>
  VSS23  = GND
  CB4_A  = M_J_CPU1_SA_CB<4>
  VSS24  = GND
  CB5_A  = M_J_CPU1_SA_CB<5>
  VSS25  = GND
  ALERT_N  = M_J_CPU1_ALERT_N
  VSS26  = GND
  CS0_A_N  = M_J_CPU1_SA_CS_N<0>
  VSS27  = GND
  CA0_A  = M_J_CPU1_SA_CA<0>
  VSS28  = GND
  CA2_A  = M_J_CPU1_SA_CA<2>
  VSS29  = GND
  CA4_A  = M_J_CPU1_SA_CA<4>
  VSS30  = GND
  CA6_A  = M_J_CPU1_SA_CA<6>
  VSS31  = GND
  PAR_A  = M_J_CPU1_SA_PAR
  VSS32  = GND
  CA0_B  = M_J_CPU1_SB_CA<0>
  VSS33  = GND
  CA2_B  = M_J_CPU1_SB_CA<2>
  VSS34  = GND
  CA4_B  = M_J_CPU1_SB_CA<4>
  VSS35  = GND
  CA6_B  = M_J_CPU1_SB_CA<6>
  VSS36  = GND
  CS0_B_N  = M_J_CPU1_SB_CS_N<0>
  VSS37  = GND
  \lbd||rsp_a_n\  = M_J_CPU1_SA_RSP<0>
  \lbs||rsp_b_n\  = M_J_CPU1_SB_RSP<0>
  VSS38  = GND
  CB4_B  = M_J_CPU1_SB_CB<4>
  VSS39  = GND
  CB5_B  = M_J_CPU1_SB_CB<5>
  VSS40  = GND
  \dqs9_b_t||tdqs9_b_t||dbi4_b_n\  = M_J_CPU1_SB_DQS_DP<9>
  \dqs9_b_c||tdqs9_b_c\  = M_J_CPU1_SB_DQS_DN<9>
  VSS41  = GND
  CB0_B  = M_J_CPU1_SB_CB<0>
  VSS42  = GND
  CB1_B  = M_J_CPU1_SB_CB<1>
  VSS43  = GND
  DQ0_B  = M_J_CPU1_SB_DQ<0>
  VSS44  = GND
  DQ1_B  = M_J_CPU1_SB_DQ<1>
  VSS45  = GND
  DQS0_B_T  = M_J_CPU1_SB_DQS_DP<0>
  DQS0_B_C  = M_J_CPU1_SB_DQS_DN<0>
  VSS46  = GND
  DQ4_B  = M_J_CPU1_SB_DQ<4>
  VSS47  = GND
  DQ5_B  = M_J_CPU1_SB_DQ<5>
  VSS48  = GND
  DQ8_B  = M_J_CPU1_SB_DQ<8>
  VSS49  = GND
  DQ9_B  = M_J_CPU1_SB_DQ<9>
  VSS50  = GND
  DQS1_B_T  = M_J_CPU1_SB_DQS_DP<1>
  DQS1_B_C  = M_J_CPU1_SB_DQS_DN<1>
  VSS51  = GND
  DQ12_B  = M_J_CPU1_SB_DQ<12>
  VSS52  = GND
  DQ13_B  = M_J_CPU1_SB_DQ<13>
  VSS53  = GND
  DQ16_B  = M_J_CPU1_SB_DQ<16>
  VSS54  = GND
  DQ17_B  = M_J_CPU1_SB_DQ<17>
  VSS55  = GND
  DQS2_B_T  = M_J_CPU1_SB_DQS_DP<2>
  DQS2_B_C  = M_J_CPU1_SB_DQS_DN<2>
  VSS56  = GND
  DQ20_B  = M_J_CPU1_SB_DQ<20>
  VSS57  = GND
  DQ21_B  = M_J_CPU1_SB_DQ<21>
  VSS58  = GND
  DQ24_B  = M_J_CPU1_SB_DQ<24>
  VSS59  = GND
  DQ25_B  = M_J_CPU1_SB_DQ<25>
  VSS60  = GND
  DQS3_B_T  = M_J_CPU1_SB_DQS_DP<3>
  DQS3_B_C  = M_J_CPU1_SB_DQS_DN<3>
  VSS61  = GND
  DQ28_B  = M_J_CPU1_SB_DQ<28>
  VSS62  = GND
  DQ29_B  = M_J_CPU1_SB_DQ<29>
  VSS63  = GND
  RFU1  = NC
  VIN_BULK1  = P12V_MEM_CPU1
  VIN_BULK2  = P12V_MEM_CPU1
  \pwr_good||fail_n\  = PWRGD_CHJ_CPU1_DIMM
  HAS  = PD_CHJ_CPU1_DIMM_SAA
  RFU2  = NC
  RFU3  = NC
  VSS64  = GND
  DQ2_A  = M_J_CPU1_SA_DQ<2>
  VSS65  = GND
  DQ3_A  = M_J_CPU1_SA_DQ<3>
  VSS66  = GND
  \dqs5_a_c||tdqs5_a_c||dqs5_a_t||tdqs5_a_t\  = M_J_CPU1_SA_DQS_DN<5>
  \dqs5_a_t||tdqs5_a_t\  = M_J_CPU1_SA_DQS_DP<5>
  VSS67  = GND
  DQ6_A  = M_J_CPU1_SA_DQ<6>
  VSS68  = GND
  DQ7_A  = M_J_CPU1_SA_DQ<7>
  VSS69  = GND
  DQ10_A  = M_J_CPU1_SA_DQ<10>
  VSS70  = GND
  DQ11_A  = M_J_CPU1_SA_DQ<11>
  VSS71  = GND
  \dqs6_a_c||tdqs6_a_c||dqs6_a_t||tdqs6_a_t\  = M_J_CPU1_SA_DQS_DN<6>
  \dqs6_a_t||tdqs6_a_t\  = M_J_CPU1_SA_DQS_DP<6>
  VSS72  = GND
  DQ14_A  = M_J_CPU1_SA_DQ<14>
  VSS73  = GND
  DQ15_A  = M_J_CPU1_SA_DQ<15>
  VSS74  = GND
  DQ18_A  = M_J_CPU1_SA_DQ<18>
  VSS75  = GND
  DQ19_A  = M_J_CPU1_SA_DQ<19>
  VSS76  = GND
  \dqs7_a_c||tdqs7_a_c\  = M_J_CPU1_SA_DQS_DN<7>
  \dqs7_a_t||tdqs7_a_t\  = M_J_CPU1_SA_DQS_DP<7>
  VSS77  = GND
  DQ22_A  = M_J_CPU1_SA_DQ<22>
  VSS78  = GND
  DQ23_A  = M_J_CPU1_SA_DQ<23>
  VSS79  = GND
  DQ26_A  = M_J_CPU1_SA_DQ<26>
  VSS80  = GND
  DQ27_A  = M_J_CPU1_SA_DQ<27>
  VSS81  = GND
  \dqs8_a_c||tdqs8_a_c\  = M_J_CPU1_SA_DQS_DN<8>
  \dqs8_a_t||tdqs8_a_t\  = M_J_CPU1_SA_DQS_DP<8>
  VSS82  = GND
  DQ30_A  = M_J_CPU1_SA_DQ<30>
  VSS83  = GND
  DQ31_A  = M_J_CPU1_SA_DQ<31>
  VSS84  = GND
  CB2_A  = M_J_CPU1_SA_CB<2>
  VSS85  = GND
  CB3_A  = M_J_CPU1_SA_CB<3>
  VSS86  = GND
  \dqs9_a_c||tdqs9_a_c\  = M_J_CPU1_SA_DQS_DN<9>
  \dqs9_a_t||tdqs9_a_t\  = M_J_CPU1_SA_DQS_DP<9>
  VSS87  = GND
  CB6_A  = M_J_CPU1_SA_CB<6>
  VSS88  = GND
  CB7_A  = M_J_CPU1_SA_CB<7>
  VSS89  = GND
  RESET_N  = M_J_CPU1_RESET_N
  VSS90  = GND
  CS1_A_N  = M_J_CPU1_SA_CS_N<1>
  VSS91  = GND
  CA1_A  = M_J_CPU1_SA_CA<1>
  VSS92  = GND
  CA3_A  = M_J_CPU1_SA_CA<3>
  VSS93  = GND
  CA5_A  = M_J_CPU1_SA_CA<5>
  VSS94  = GND
  CK_T  = M_J_CPU1_CLK_DP<0>
  CK_C  = M_J_CPU1_CLK_DN<0>
  VSS95  = GND
  RFU4  = NC
  CA1_B  = M_J_CPU1_SB_CA<1>
  VSS96  = GND
  CA3_B  = M_J_CPU1_SB_CA<3>
  VSS97  = GND
  CA5_B  = M_J_CPU1_SB_CA<5>
  VSS98  = GND
  PAR_B  = M_J_CPU1_SB_PAR
  VSS99  = GND
  CS1_B_N  = M_J_CPU1_SB_CS_N<1>
  VSS100  = GND
  RFU5  = NC
  RFU6  = NC
  VSS101  = GND
  CB6_B  = M_J_CPU1_SB_CB<6>
  VSS102  = GND
  CB7_B  = M_J_CPU1_SB_CB<7>
  VSS103  = GND
  DQS4_B_C  = M_J_CPU1_SB_DQS_DN<4>
  DQS4_B_T  = M_J_CPU1_SB_DQS_DP<4>
  VSS104  = GND
  CB2_B  = M_J_CPU1_SB_CB<2>
  VSS105  = GND
  CB3_B  = M_J_CPU1_SB_CB<3>
  VSS106  = GND
  DQ2_B  = M_J_CPU1_SB_DQ<2>
  VSS107  = GND
  DQ3_B  = M_J_CPU1_SB_DQ<3>
  VSS108  = GND
  \dqs5_b_c||tdqs5_b_c\  = M_J_CPU1_SB_DQS_DN<5>
  \dqs5_b_t||tdqs5_b_t\  = M_J_CPU1_SB_DQS_DP<5>
  VSS109  = GND
  DQ6_B  = M_J_CPU1_SB_DQ<6>
  VSS110  = GND
  DQ7_B  = M_J_CPU1_SB_DQ<7>
  VSS111  = GND
  DQ10_B  = M_J_CPU1_SB_DQ<10>
  VSS112  = GND
  DQ11_B  = M_J_CPU1_SB_DQ<11>
  VSS113  = GND
  \dqs6_b_c||tdqs6_b_c\  = M_J_CPU1_SB_DQS_DN<6>
  \dqs6_b_t||tdqs6_b_t\  = M_J_CPU1_SB_DQS_DP<6>
  VSS114  = GND
  DQ14_B  = M_J_CPU1_SB_DQ<14>
  VSS115  = GND
  DQ15_B  = M_J_CPU1_SB_DQ<15>
  VSS116  = GND
  DQ18_B  = M_J_CPU1_SB_DQ<18>
  VSS117  = GND
  DQ19_B  = M_J_CPU1_SB_DQ<19>
  VSS118  = GND
  \dqs7_b_c||tdqs7_b_c\  = M_J_CPU1_SB_DQS_DN<7>
  \dqs7_b_t||tdqs7_b_t\  = M_J_CPU1_SB_DQS_DP<7>
  VSS119  = GND
  DQ22_B  = M_J_CPU1_SB_DQ<22>
  VSS120  = GND
  DQ23_B  = M_J_CPU1_SB_DQ<23>
  VSS121  = GND
  DQ26_B  = M_J_CPU1_SB_DQ<26>
  VSS122  = GND
  DQ27_B  = M_J_CPU1_SB_DQ<27>
  VSS123  = GND
  \dqs8_b_c||tdqs8_b_c\  = M_J_CPU1_SB_DQS_DN<8>
  \dqs8_b_t||tdqs8_b_t\  = M_J_CPU1_SB_DQS_DP<8>
  VSS124  = GND
  DQ30_B  = M_J_CPU1_SB_DQ<30>
  VSS125  = GND
  DQ31_B  = M_J_CPU1_SB_DQ<31>
  VSS126  = GND
  G1  = GND
  G2  = GND
  G3  = GND

(kicad_pcb
	(version 20260206)
	(generator "pcbnew")
	(generator_version "10.0")
	(general
		(thickness 1.6)
		(legacy_teardrops no)
	)
	(paper "A4")
	(title_block
		(title "04192023_DAF0TMB3IC0_F0TG_MB_C_brd_V02_OCP.brd")
		(comment 1 "Grand Teton / footprint 1456 of 8354 (J29), pads 230-275 of 291")
	)
	(layers
		(0 "F.Cu" signal "TOP")
		(4 "In1.Cu" signal "GND")
		(6 "In2.Cu" signal "IN1")
		(8 "In3.Cu" signal "GND1")
		(10 "In4.Cu" signal "IN2")
		(12 "In5.Cu" signal "GND2")
		(14 "In6.Cu" signal "IN3")
		(16 "In7.Cu" signal "GND3")
		(18 "In8.Cu" signal "VCC")
		(20 "In9.Cu" signal "VCC1")
		(22 "In10.Cu" signal "GND4")
		(24 "In11.Cu" signal "IN4")
		(26 "In12.Cu" signal "GND5")
		(28 "In13.Cu" signal "IN5")
		(30 "In14.Cu" signal "GND6")
		(32 "In15.Cu" signal "IN6")
		(34 "In16.Cu" signal "GND7")
		(2 "B.Cu" signal "BOTTOM")
		(9 "F.Adhes" user "F.Adhesive")
		(11 "B.Adhes" user "B.Adhesive")
		(13 "F.Paste" user "Package Geometry/Pastemask Top")
		(15 "B.Paste" user "Package Geometry/Pastemask Bottom")
		(5 "F.SilkS" user "Ref Des/Silkscreen Top")
		(7 "B.SilkS" user "Ref Des/Silkscreen Bottom")
		(1 "F.Mask" user "Board Geometry/Soldermask Top")
		(3 "B.Mask" user "Board Geometry/Soldermask Bottom")
		(17 "Dwgs.User" user "User.Drawings")
		(19 "Cmts.User" user "User.Comments")
		(21 "Eco1.User" user "User.Eco1")
		(23 "Eco2.User" user "User.Eco2")
		(25 "Edge.Cuts" user "Board Geometry/Outline")
		(27 "Margin" user)
		(31 "F.CrtYd" user "Package Geometry/Place Bound Top")
		(29 "B.CrtYd" user "Package Geometry/Place Bound Bottom")
		(35 "F.Fab" user "Ref Des/Assembly Top")
		(33 "B.Fab" user "Ref Des/Assembly Bottom")
	)
	(footprint ""
		(layer "F.Cu")
		(at 189.110112 -255.560322 180)
		(property "Reference" "J29"
			(at -2.7178 -81.857088 0)
			(unlocked yes)
			(layer "F.SilkS")
			(effects
				(font
					(size 0.7874 0.5842)
					(thickness 0.1524)
				)
			)
		)
		(property "Value" ""
			(at 0 0 180)
			(layer "F.Fab")
			(effects
				(font
					(size 1.27 1.27)
				)
			)
		)
		(duplicate_pad_numbers_are_jumpers no)
		(pad "230" smd rect
			(at 2.050034 14.025118 90)
			(size 0.519938 1.4986)
			(layers "F.Cu" "F.Mask" "F.Paste")
			(net "GND")
		)
		(pad "231" smd rect
			(at 2.050034 14.875002 90)
			(size 0.519938 1.4986)
			(layers "F.Cu" "F.Mask" "F.Paste")
			(net "Net_2387")
		)
		(pad "232" smd rect
			(at 2.050034 15.724886 90)
			(size 0.519938 1.4986)
			(layers "F.Cu" "F.Mask" "F.Paste")
			(net "Net_2388")
		)
		(pad "233" smd rect
			(at 2.050034 16.575024 90)
			(size 0.519938 1.4986)
			(layers "F.Cu" "F.Mask" "F.Paste")
			(net "GND")
		)
		(pad "234" smd rect
			(at 2.050034 17.424908 90)
			(size 0.519938 1.4986)
			(layers "F.Cu" "F.Mask" "F.Paste")
			(net "M_J_CPU1_SB_CB<6>")
		)
		(pad "235" smd rect
			(at 2.050034 18.275046 90)
			(size 0.519938 1.4986)
			(layers "F.Cu" "F.Mask" "F.Paste")
			(net "GND")
		)
		(pad "236" smd rect
			(at 2.050034 19.12493 90)
			(size 0.519938 1.4986)
			(layers "F.Cu" "F.Mask" "F.Paste")
			(net "M_J_CPU1_SB_CB<7>")
		)
		(pad "237" smd rect
			(at 2.050034 19.975068 90)
			(size 0.519938 1.4986)
			(layers "F.Cu" "F.Mask" "F.Paste")
			(net "GND")
		)
		(pad "238" smd rect
			(at 2.050034 20.824952 90)
			(size 0.519938 1.4986)
			(layers "F.Cu" "F.Mask" "F.Paste")
			(net "M_J_CPU1_SB_DQS_DN<4>")
		)
		(pad "239" smd rect
			(at 2.050034 21.67509 90)
			(size 0.519938 1.4986)
			(layers "F.Cu" "F.Mask" "F.Paste")
			(net "M_J_CPU1_SB_DQS_DP<4>")
		)
		(pad "240" smd rect
			(at 2.050034 22.524974 90)
			(size 0.519938 1.4986)
			(layers "F.Cu" "F.Mask" "F.Paste")
			(net "GND")
		)
		(pad "241" smd rect
			(at 2.050034 23.375112 90)
			(size 0.519938 1.4986)
			(layers "F.Cu" "F.Mask" "F.Paste")
			(net "M_J_CPU1_SB_CB<2>")
		)
		(pad "242" smd rect
			(at 2.050034 24.224996 90)
			(size 0.519938 1.4986)
			(layers "F.Cu" "F.Mask" "F.Paste")
			(net "GND")
		)
		(pad "243" smd rect
			(at 2.050034 25.07488 90)
			(size 0.519938 1.4986)
			(layers "F.Cu" "F.Mask" "F.Paste")
			(net "M_J_CPU1_SB_CB<3>")
		)
		(pad "244" smd rect
			(at 2.050034 25.925018 90)
			(size 0.519938 1.4986)
			(layers "F.Cu" "F.Mask" "F.Paste")
			(net "GND")
		)
		(pad "245" smd rect
			(at 2.050034 26.774902 90)
			(size 0.519938 1.4986)
			(layers "F.Cu" "F.Mask" "F.Paste")
			(net "M_J_CPU1_SB_DQ<2>")
		)
		(pad "246" smd rect
			(at 2.050034 27.62504 90)
			(size 0.519938 1.4986)
			(layers "F.Cu" "F.Mask" "F.Paste")
			(net "GND")
		)
		(pad "247" smd rect
			(at 2.050034 28.474924 90)
			(size 0.519938 1.4986)
			(layers "F.Cu" "F.Mask" "F.Paste")
			(net "M_J_CPU1_SB_DQ<3>")
		)
		(pad "248" smd rect
			(at 2.050034 29.325062 90)
			(size 0.519938 1.4986)
			(layers "F.Cu" "F.Mask" "F.Paste")
			(net "GND")
		)
		(pad "249" smd rect
			(at 2.050034 30.174946 90)
			(size 0.519938 1.4986)
			(layers "F.Cu" "F.Mask" "F.Paste")
			(net "M_J_CPU1_SB_DQS_DN<5>")
		)
		(pad "250" smd rect
			(at 2.050034 31.025084 90)
			(size 0.519938 1.4986)
			(layers "F.Cu" "F.Mask" "F.Paste")
			(net "M_J_CPU1_SB_DQS_DP<5>")
		)
		(pad "251" smd rect
			(at 2.050034 31.874968 90)
			(size 0.519938 1.4986)
			(layers "F.Cu" "F.Mask" "F.Paste")
			(net "GND")
		)
		(pad "252" smd rect
			(at 2.050034 32.725106 90)
			(size 0.519938 1.4986)
			(layers "F.Cu" "F.Mask" "F.Paste")
			(net "M_J_CPU1_SB_DQ<6>")
		)
		(pad "253" smd rect
			(at 2.050034 33.57499 90)
			(size 0.519938 1.4986)
			(layers "F.Cu" "F.Mask" "F.Paste")
			(net "GND")
		)
		(pad "254" smd rect
			(at 2.050034 34.425128 90)
			(size 0.519938 1.4986)
			(layers "F.Cu" "F.Mask" "F.Paste")
			(net "M_J_CPU1_SB_DQ<7>")
		)
		(pad "255" smd rect
			(at 2.050034 35.275012 90)
			(size 0.519938 1.4986)
			(layers "F.Cu" "F.Mask" "F.Paste")
			(net "GND")
		)
		(pad "256" smd rect
			(at 2.050034 36.124896 90)
			(size 0.519938 1.4986)
			(layers "F.Cu" "F.Mask" "F.Paste")
			(net "M_J_CPU1_SB_DQ<10>")
		)
		(pad "257" smd rect
			(at 2.050034 36.975034 90)
			(size 0.519938 1.4986)
			(layers "F.Cu" "F.Mask" "F.Paste")
			(net "GND")
		)
		(pad "258" smd rect
			(at 2.050034 37.824918 90)
			(size 0.519938 1.4986)
			(layers "F.Cu" "F.Mask" "F.Paste")
			(net "M_J_CPU1_SB_DQ<11>")
		)
		(pad "259" smd rect
			(at 2.050034 38.675056 90)
			(size 0.519938 1.4986)
			(layers "F.Cu" "F.Mask" "F.Paste")
			(net "GND")
		)
		(pad "260" smd rect
			(at 2.050034 39.52494 90)
			(size 0.519938 1.4986)
			(layers "F.Cu" "F.Mask" "F.Paste")
			(net "M_J_CPU1_SB_DQS_DN<6>")
		)
		(pad "261" smd rect
			(at 2.050034 40.375078 90)
			(size 0.519938 1.4986)
			(layers "F.Cu" "F.Mask" "F.Paste")
			(net "M_J_CPU1_SB_DQS_DP<6>")
		)
		(pad "262" smd rect
			(at 2.050034 41.224962 90)
			(size 0.519938 1.4986)
			(layers "F.Cu" "F.Mask" "F.Paste")
			(net "GND")
		)
		(pad "263" smd rect
			(at 2.050034 42.0751 90)
			(size 0.519938 1.4986)
			(layers "F.Cu" "F.Mask" "F.Paste")
			(net "M_J_CPU1_SB_DQ<14>")
		)
		(pad "264" smd rect
			(at 2.050034 42.924984 90)
			(size 0.519938 1.4986)
			(layers "F.Cu" "F.Mask" "F.Paste")
			(net "GND")
		)
		(pad "265" smd rect
			(at 2.050034 43.775122 90)
			(size 0.519938 1.4986)
			(layers "F.Cu" "F.Mask" "F.Paste")
			(net "M_J_CPU1_SB_DQ<15>")
		)
		(pad "266" smd rect
			(at 2.050034 44.625006 90)
			(size 0.519938 1.4986)
			(layers "F.Cu" "F.Mask" "F.Paste")
			(net "GND")
		)
		(pad "267" smd rect
			(at 2.050034 45.47489 90)
			(size 0.519938 1.4986)
			(layers "F.Cu" "F.Mask" "F.Paste")
			(net "M_J_CPU1_SB_DQ<18>")
		)
		(pad "268" smd rect
			(at 2.050034 46.325028 90)
			(size 0.519938 1.4986)
			(layers "F.Cu" "F.Mask" "F.Paste")
			(net "GND")
		)
		(pad "269" smd rect
			(at 2.050034 47.174912 90)
			(size 0.519938 1.4986)
			(layers "F.Cu" "F.Mask" "F.Paste")
			(net "M_J_CPU1_SB_DQ<19>")
		)
		(pad "270" smd rect
			(at 2.050034 48.02505 90)
			(size 0.519938 1.4986)
			(layers "F.Cu" "F.Mask" "F.Paste")
			(net "GND")
		)
		(pad "271" smd rect
			(at 2.050034 48.874934 90)
			(size 0.519938 1.4986)
			(layers "F.Cu" "F.Mask" "F.Paste")
			(net "M_J_CPU1_SB_DQS_DN<7>")
		)
		(pad "272" smd rect
			(at 2.050034 49.725072 90)
			(size 0.519938 1.4986)
			(layers "F.Cu" "F.Mask" "F.Paste")
			(net "M_J_CPU1_SB_DQS_DP<7>")
		)
		(pad "273" smd rect
			(at 2.050034 50.574956 90)
			(size 0.519938 1.4986)
			(layers "F.Cu" "F.Mask" "F.Paste")
			(net "GND")
		)
		(pad "274" smd rect
			(at 2.050034 51.425094 90)
			(size 0.519938 1.4986)
			(layers "F.Cu" "F.Mask" "F.Paste")
			(net "M_J_CPU1_SB_DQ<22>")
		)
		(pad "275" smd rect
			(at 2.050034 52.274978 90)
			(size 0.519938 1.4986)
			(layers "F.Cu" "F.Mask" "F.Paste")
			(net "GND")
		)
	)
)
